FILE_TYPE = CONNECTIVITY;
{Allegro Design Entry HDL 17.2-2016 S081 (4005846) 1/11/2022}
"PAGE_NUMBER" = 70;
0"NC";
1"GND\g";
2"GND\g";
3"GND\g";
4"GND\g";
5"GND\g";
6"GND\g";
%"UNIVERSAL_GND"
"1","(-3525,-725)","0","logical_power","I1";
;
CDS_LIB"logical_power"
HDL_POWER"GND";
"A"6;
%"SOCKET4677_AZIF0045P001C01CS"
"31","(-2075,1800)","0","pure_quanta","I2";
;
PART_NUMBER"DGA^7000023"
PART_TYPE"SMLF"
MATERIAL"IO"
VALUE"SOCKET4677_AZIF0045-P001C01CS"
$LOCATION"U1"
CDS_LIB"pure_quanta"
NEEDS_NO_SIZE"TRUE"
CDS_LMAN_SYM_OUTLINE"-1050,2150,1050,-2100"
CDS_LOCATION"U1"
$SEC"31"
CDS_SEC"31";
"VSS1312"
$PN"EH42"5;
"VSS1315"
$PN"EH55"5;
"VSS1319"
$PN"EH61"5;
"VSS1320"
$PN"EH67"5;
"VSS1322"
$PN"EH79"5;
"VSS1325"
$PN"EJ11"5;
"VSS1328"
$PN"EJ17"5;
"VSS1331"
$PN"EJ25"5;
"VSS1334"
$PN"EJ35"5;
"VSS1340"
$PN"EJ54"5;
"VSS1343"
$PN"EJ62"5;
"VSS1345"
$PN"EJ68"5;
"VSS1347"
$PN"EJ72"5;
"VSS1355"
$PN"EK16"5;
"VSS1357"
$PN"EK20"5;
"VSS1359"
$PN"EK26"5;
"VSS1366"
$PN"EK44"5;
"VSS1368"
$PN"EK51"5;
"VSS1369"
$PN"EK53"5;
"VSS1371"
$PN"EK59"5;
"VSS1372"
$PN"EK63"5;
"VSS1375"
$PN"EK71"5;
"VSS1377"
$PN"EK77"5;
"VSS1378"
$PN"EK79"5;
"VSS1379"
$PN"EK83"5;
"VSS1380"
$PN"EK89"5;
"VSS1381"
$PN"EL15"5;
"VSS1391"
$PN"EL52"5;
"VSS1394"
$PN"EL58"5;
"VSS1396"
$PN"EL7"5;
"VSS1397"
$PN"EL70"5;
"VSS1398"
$PN"EL72"5;
"VSS1400"
$PN"EL86"6;
"VSS1401"
$PN"EL9"5;
"VSS1405"
$PN"EM49"6;
"VSS1409"
$PN"EM79"6;
"VSS1419"
$PN"EH36"5;
"VSS1421"
$PN"EH49"5;
"VSS1422"
$PN"EH73"5;
"VSS1423"
$PN"EH81"5;
"VSS1424"
$PN"EH83"5;
"VSS1425"
$PN"EJ13"5;
"VSS1426"
$PN"EJ19"5;
"VSS1427"
$PN"EN39"6;
"VSS1428"
$PN"EJ23"5;
"VSS1429"
$PN"EJ29"5;
"VSS1430"
$PN"EJ31"5;
"VSS1431"
$PN"EJ37"5;
"VSS1432"
$PN"EJ41"5;
"VSS1433"
$PN"EJ43"5;
"VSS1434"
$PN"EJ48"5;
"VSS1435"
$PN"EJ50"5;
"VSS1436"
$PN"EN58"6;
"VSS1437"
$PN"EN60"6;
"VSS1438"
$PN"EN62"6;
"VSS1439"
$PN"EJ56"5;
"VSS1440"
$PN"EN66"6;
"VSS1441"
$PN"EN72"6;
"VSS1442"
$PN"EJ60"5;
"VSS1443"
$PN"EJ66"5;
"VSS1444"
$PN"EJ7"5;
"VSS1445"
$PN"EN88"6;
"VSS1446"
$PN"EN9"6;
"VSS1447"
$PN"EJ74"5;
"VSS1448"
$PN"EJ78"5;
"VSS1449"
$PN"EJ88"5;
"VSS1450"
$PN"EJ9"5;
"VSS1451"
$PN"EK10"5;
"VSS1452"
$PN"EP69"6;
"VSS1453"
$PN"EP71"6;
"VSS1454"
$PN"EP77"6;
"VSS1455"
$PN"EK14"5;
"VSS1456"
$PN"ER15"6;
"VSS1457"
$PN"ER21"6;
"VSS1458"
$PN"EK2"5;
"VSS1459"
$PN"EK22"5;
"VSS1460"
$PN"EK28"5;
"VSS1461"
$PN"EK32"5;
"VSS1462"
$PN"ER39"6;
"VSS1463"
$PN"EK34"5;
"VSS1464"
$PN"ER52"6;
"VSS1465"
$PN"EK38"5;
"VSS1466"
$PN"EK4"5;
"VSS1467"
$PN"ER58"6;
"VSS1468"
$PN"ER64"6;
"VSS1469"
$PN"EK40"5;
"VSS1470"
$PN"EK47"5;
"VSS1471"
$PN"EK57"5;
"VSS1472"
$PN"EK65"5;
"VSS1473"
$PN"EK69"5;
"VSS1474"
$PN"EK75"5;
"VSS1475"
$PN"EL21"5;
"VSS1476"
$PN"ER9"6;
"VSS1477"
$PN"EL27"5;
"VSS1478"
$PN"ET14"6;
"VSS1479"
$PN"EL3"5;
"VSS1480"
$PN"ET20"6;
"VSS1481"
$PN"EL33"5;
"VSS1482"
$PN"ET26"6;
"VSS1483"
$PN"EL39"5;
"VSS1484"
$PN"ET32"6;
"VSS1485"
$PN"EL45"5;
"VSS1486"
$PN"EL5"5;
"VSS1488"
$PN"EL64"5;
"VSS1489"
$PN"EL76"5;
"VSS1491"
$PN"ET53"6;
"VSS1492"
$PN"EM42"6;
"VSS1493"
$PN"ET59"6;
"VSS1496"
$PN"EM73"6;
"VSS1497"
$PN"EM8"6;
"VSS1498"
$PN"EM81"6;
"VSS1499"
$PN"EM83"6;
"VSS1500"
$PN"EN11"6;
"VSS1501"
$PN"EN13"6;
"VSS1503"
$PN"EN15"6;
"VSS1505"
$PN"EN17"6;
"VSS1506"
$PN"EN19"6;
"VSS1512"
$PN"EN21"6;
"VSS1513"
$PN"EN23"6;
"VSS1515"
$PN"EN25"6;
"VSS1517"
$PN"EN27"6;
"VSS1518"
$PN"EN29"6;
"VSS1520"
$PN"EN31"6;
"VSS1522"
$PN"EN33"6;
"VSS1524"
$PN"EN35"6;
"VSS1525"
$PN"EN37"6;
"VSS1526"
$PN"EN41"6;
"VSS1528"
$PN"EN43"6;
"VSS1529"
$PN"EN45"6;
"VSS1530"
$PN"EN48"6;
"VSS1531"
$PN"EN50"6;
"VSS1533"
$PN"EN52"6;
"VSS1537"
$PN"EN54"6;
"VSS1539"
$PN"EN56"6;
"VSS1540"
$PN"EN64"6;
"VSS1541"
$PN"EN78"6;
"VSS1542"
$PN"EN80"6;
"VSS1543"
$PN"EP67"6;
"VSS1545"
$PN"EP83"6;
"VSS1547"
$PN"ER27"6;
"VSS1548"
$PN"ER33"6;
"VSS1549"
$PN"ER5"6;
"VSS1550"
$PN"ER7"6;
"VSS1551"
$PN"ER70"6;
"VSS1552"
$PN"ER74"6;
"VSS1553"
$PN"ER78"6;
"VSS1554"
$PN"ER80"6;
"VSS1555"
$PN"ER84"6;
"VSS1556"
$PN"ER86"6;
"VSS1557"
$PN"ET10"6;
"VSS1559"
$PN"ET16"6;
"VSS1561"
$PN"ET22"6;
"VSS1562"
$PN"ET28"6;
"VSS1563"
$PN"ET34"6;
"VSS1565"
$PN"ET38"6;
"VSS1569"
$PN"ET57"6;
"VSS1837"
$PN"ER50"6;
"VSS1836"
$PN"ER48"6;
"VSS1835"
$PN"ER43"6;
"VSS1834"
$PN"ER41"6;
%"UNIVERSAL_GND"
"1","(-625,-725)","0","logical_power","I3";
;
CDS_LIB"logical_power"
HDL_POWER"GND";
"A"5;
%"UNIVERSAL_GND"
"1","(-475,-725)","0","logical_power","I4";
;
CDS_LIB"logical_power"
HDL_POWER"GND";
"A"4;
%"SOCKET4677_AZIF0045P001C01CS"
"32","(975,1800)","0","pure_quanta","I5";
;
PART_NUMBER"DGA^7000023"
PART_TYPE"SMLF"
MATERIAL"IO"
VALUE"SOCKET4677_AZIF0045-P001C01CS"
$LOCATION"U1"
CDS_LIB"pure_quanta"
NEEDS_NO_SIZE"TRUE"
CDS_LMAN_SYM_OUTLINE"-1050,2150,1050,-2100"
CDS_LOCATION"U1"
$SEC"32"
CDS_SEC"32";
"VSS1111"
$PN"DY12"3;
"VSS1112"
$PN"DY16"3;
"VSS1115"
$PN"DY4"3;
"VSS1116"
$PN"DY42"3;
"VSS1141"
$PN"EA39"3;
"VSS1142"
$PN"EA45"3;
"VSS1144"
$PN"EA52"3;
"VSS1145"
$PN"EA58"3;
"VSS1146"
$PN"EA64"3;
"VSS1155"
$PN"EB16"3;
"VSS1156"
$PN"EB20"3;
"VSS1158"
$PN"EB26"3;
"VSS1161"
$PN"EB34"3;
"VSS1163"
$PN"EB4"3;
"VSS1165"
$PN"EB44"3;
"VSS1167"
$PN"EB51"3;
"VSS1168"
$PN"EB53"3;
"VSS1170"
$PN"EB59"3;
"VSS1171"
$PN"EB63"3;
"VSS1180"
$PN"EB91"3;
"VSS1185"
$PN"EC25"3;
"VSS1188"
$PN"EC35"3;
"VSS1193"
$PN"EC5"3;
"VSS1195"
$PN"EC54"3;
"VSS1197"
$PN"EC60"3;
"VSS1198"
$PN"EC62"3;
"VSS1200"
$PN"EC68"3;
"VSS1208"
$PN"ED12"4;
"VSS1210"
$PN"ED18"4;
"VSS1217"
$PN"ED42"4;
"VSS1220"
$PN"ED55"4;
"VSS1223"
$PN"ED61"4;
"VSS1224"
$PN"ED67"4;
"VSS1225"
$PN"ED73"4;
"VSS1232"
$PN"EE17"4;
"VSS1235"
$PN"EE39"4;
"VSS1237"
$PN"EE52"4;
"VSS1257"
$PN"DW66"3;
"VSS1258"
$PN"DW68"3;
"VSS1259"
$PN"DW70"3;
"VSS1260"
$PN"DW72"3;
"VSS1261"
$PN"DW74"3;
"VSS1262"
$PN"DW76"3;
"VSS1263"
$PN"DW80"3;
"VSS1264"
$PN"DW82"3;
"VSS1265"
$PN"EF51"4;
"VSS1266"
$PN"DW84"3;
"VSS1267"
$PN"DW88"3;
"VSS1269"
$PN"DY77"3;
"VSS1270"
$PN"DY8"3;
"VSS1274"
$PN"EA21"3;
"VSS1275"
$PN"EA27"3;
"VSS1276"
$PN"EF73"4;
"VSS1277"
$PN"EF75"4;
"VSS1278"
$PN"EA33"3;
"VSS1279"
$PN"EA70"3;
"VSS1280"
$PN"EA76"3;
"VSS1281"
$PN"EA78"3;
"VSS1282"
$PN"EA80"3;
"VSS1283"
$PN"EF89"4;
"VSS1284"
$PN"EG13"4;
"VSS1285"
$PN"EA84"3;
"VSS1286"
$PN"EA88"3;
"VSS1287"
$PN"EB12"3;
"VSS1288"
$PN"EB22"3;
"VSS1289"
$PN"EB28"3;
"VSS1290"
$PN"EG5"4;
"VSS1291"
$PN"EG52"4;
"VSS1292"
$PN"EB32"3;
"VSS1293"
$PN"EB38"3;
"VSS1294"
$PN"EG7"4;
"VSS1295"
$PN"EB40"3;
"VSS1296"
$PN"EB47"3;
"VSS1297"
$PN"EB57"3;
"VSS1298"
$PN"EB65"3;
"VSS1299"
$PN"EB69"3;
"VSS1300"
$PN"EB71"3;
"VSS1301"
$PN"EB75"3;
"VSS1302"
$PN"EH12"4;
"VSS1303"
$PN"EH14"4;
"VSS1304"
$PN"EB79"3;
"VSS1305"
$PN"EH18"4;
"VSS1306"
$PN"EB8"3;
"VSS1307"
$PN"EB83"3;
"VSS1308"
$PN"EB87"3;
"VSS1309"
$PN"EC1"3;
"VSS1310"
$PN"EC13"3;
"VSS1311"
$PN"EC19"3;
"VSS1313"
$PN"EC23"3;
"VSS1314"
$PN"EC29"3;
"VSS1316"
$PN"EC31"3;
"VSS1317"
$PN"EC37"3;
"VSS1318"
$PN"EH6"4;
"VSS1321"
$PN"EC41"3;
"VSS1323"
$PN"EC43"3;
"VSS1324"
$PN"EC48"3;
"VSS1326"
$PN"EC50"3;
"VSS1327"
$PN"EC56"3;
"VSS1329"
$PN"EC66"3;
"VSS1330"
$PN"EC72"3;
"VSS1332"
$PN"EC74"3;
"VSS1333"
$PN"EC82"4;
"VSS1335"
$PN"EC84"4;
"VSS1336"
$PN"EC88"4;
"VSS1337"
$PN"EC9"3;
"VSS1338"
$PN"ED16"4;
"VSS1339"
$PN"ED24"4;
"VSS1341"
$PN"ED30"4;
"VSS1342"
$PN"ED36"4;
"VSS1344"
$PN"ED4"4;
"VSS1346"
$PN"ED49"4;
"VSS1348"
$PN"ED8"4;
"VSS1349"
$PN"EE78"4;
"VSS1350"
$PN"EE80"4;
"VSS1351"
$PN"EE88"4;
"VSS1352"
$PN"EF12"4;
"VSS1353"
$PN"EF16"4;
"VSS1354"
$PN"EF18"4;
"VSS1356"
$PN"EF2"4;
"VSS1358"
$PN"EF20"4;
"VSS1360"
$PN"EF22"4;
"VSS1361"
$PN"EF24"4;
"VSS1362"
$PN"EF26"4;
"VSS1363"
$PN"EF28"4;
"VSS1364"
$PN"EF30"4;
"VSS1365"
$PN"EF32"4;
"VSS1367"
$PN"EF34"4;
"VSS1370"
$PN"EF36"4;
"VSS1373"
$PN"EF38"4;
"VSS1374"
$PN"EF4"4;
"VSS1376"
$PN"EF40"4;
"VSS1382"
$PN"EF42"4;
"VSS1383"
$PN"EF44"4;
"VSS1384"
$PN"EF47"4;
"VSS1385"
$PN"EF49"4;
"VSS1386"
$PN"EF53"4;
"VSS1387"
$PN"EF55"4;
"VSS1388"
$PN"EF57"4;
"VSS1389"
$PN"EF59"4;
"VSS1390"
$PN"EF61"4;
"VSS1392"
$PN"EF63"4;
"VSS1393"
$PN"EF65"4;
"VSS1395"
$PN"EF67"4;
"VSS1399"
$PN"EF69"4;
"VSS1402"
$PN"EF71"4;
"VSS1403"
$PN"EF77"4;
"VSS1404"
$PN"EF8"4;
"VSS1406"
$PN"EF85"4;
"VSS1407"
$PN"EF87"4;
"VSS1408"
$PN"EG39"4;
"VSS1410"
$PN"EG82"4;
"VSS1411"
$PN"EG84"4;
"VSS1412"
$PN"EG86"4;
"VSS1413"
$PN"EG88"4;
"VSS1414"
$PN"EG9"4;
"VSS1415"
$PN"EG90"4;
"VSS1416"
$PN"EH16"4;
"VSS1417"
$PN"EH24"4;
"VSS1418"
$PN"EH30"4;
"VSS1420"
$PN"EH4"4;
%"UNIVERSAL_GND"
"1","(2425,-725)","0","logical_power","I6";
;
CDS_LIB"logical_power"
HDL_POWER"GND";
"A"3;
%"UNIVERSAL_GND"
"1","(2550,-725)","0","logical_power","I7";
;
CDS_LIB"logical_power"
HDL_POWER"GND";
"A"2;
%"SOCKET4677_AZIF0045P001C01CS"
"33","(4000,1800)","0","pure_quanta","I8";
;
PART_NUMBER"DGA^7000023"
PART_TYPE"SMLF"
MATERIAL"IO"
VALUE"SOCKET4677_AZIF0045-P001C01CS"
$LOCATION"U1"
CDS_LIB"pure_quanta"
NEEDS_NO_SIZE"TRUE"
CDS_LMAN_SYM_OUTLINE"-1050,2150,1050,-2100"
CDS_LOCATION"U1"
$SEC"33"
CDS_SEC"33";
"VSS934"
$PN"DM51"1;
"VSS945"
$PN"DM73"1;
"VSS955"
$PN"DN17"1;
"VSS957"
$PN"DN39"1;
"VSS959"
$PN"DN52"1;
"VSS966"
$PN"DP12"1;
"VSS968"
$PN"DP18"1;
"VSS969"
$PN"DP24"1;
"VSS973"
$PN"DP42"1;
"VSS976"
$PN"DP55"1;
"VSS979"
$PN"DP61"1;
"VSS980"
$PN"DP67"1;
"VSS985"
$PN"DP91"1;
"VSS990"
$PN"DR25"1;
"VSS993"
$PN"DR35"1;
"VSS998"
$PN"DR5"1;
"VSS1000"
$PN"DR54"1;
"VSS1002"
$PN"DR60"1;
"VSS1003"
$PN"DR62"1;
"VSS1005"
$PN"DR68"1;
"VSS1006"
$PN"DR72"1;
"VSS1013"
$PN"DT16"2;
"VSS1014"
$PN"DT20"2;
"VSS1016"
$PN"DT26"2;
"VSS1021"
$PN"DT4"2;
"VSS1023"
$PN"DT44"2;
"VSS1025"
$PN"DT51"2;
"VSS1026"
$PN"DT53"2;
"VSS1028"
$PN"DT59"2;
"VSS1029"
$PN"DT63"2;
"VSS1036"
$PN"DT83"2;
"VSS1047"
$PN"DU39"2;
"VSS1048"
$PN"DU45"2;
"VSS1050"
$PN"DU52"2;
"VSS1051"
$PN"DU58"2;
"VSS1052"
$PN"DU64"2;
"VSS1054"
$PN"DU70"2;
"VSS1059"
$PN"DV12"2;
"VSS1060"
$PN"DV16"2;
"VSS1063"
$PN"DV4"2;
"VSS1064"
$PN"DV42"2;
"VSS1077"
$PN"DW21"2;
"VSS1097"
$PN"DW60"2;
"VSS1100"
$PN"DM12"1;
"VSS1101"
$PN"DM16"1;
"VSS1102"
$PN"DM18"1;
"VSS1103"
$PN"DM20"1;
"VSS1104"
$PN"DM22"1;
"VSS1105"
$PN"DM24"1;
"VSS1106"
$PN"DM26"1;
"VSS1107"
$PN"DM28"1;
"VSS1108"
$PN"DM30"1;
"VSS1109"
$PN"DM32"1;
"VSS1110"
$PN"DM34"1;
"VSS1113"
$PN"DM36"1;
"VSS1114"
$PN"DM38"1;
"VSS1117"
$PN"DM4"1;
"VSS1118"
$PN"DM40"1;
"VSS1119"
$PN"DM42"1;
"VSS1120"
$PN"DM44"1;
"VSS1121"
$PN"DM47"1;
"VSS1122"
$PN"DM49"1;
"VSS1123"
$PN"DM53"1;
"VSS1124"
$PN"DM55"1;
"VSS1127"
$PN"DM57"1;
"VSS1128"
$PN"DM59"1;
"VSS1130"
$PN"DM61"1;
"VSS1132"
$PN"DM63"1;
"VSS1133"
$PN"DM65"1;
"VSS1134"
$PN"DM67"1;
"VSS1135"
$PN"DM69"1;
"VSS1136"
$PN"DM71"1;
"VSS1137"
$PN"DM75"1;
"VSS1138"
$PN"DM77"1;
"VSS1139"
$PN"DM79"1;
"VSS1140"
$PN"DM8"1;
"VSS1143"
$PN"DN78"1;
"VSS1147"
$PN"DN84"1;
"VSS1148"
$PN"DN88"1;
"VSS1149"
$PN"DP16"1;
"VSS1150"
$PN"DP30"1;
"VSS1151"
$PN"DP36"1;
"VSS1152"
$PN"DP4"1;
"VSS1153"
$PN"DP49"1;
"VSS1154"
$PN"DP73"1;
"VSS1157"
$PN"DP8"1;
"VSS1159"
$PN"DP81"1;
"VSS1160"
$PN"DP87"1;
"VSS1162"
$PN"DR1"1;
"VSS1164"
$PN"DR13"1;
"VSS1166"
$PN"DR19"1;
"VSS1169"
$PN"DR23"1;
"VSS1172"
$PN"DR29"1;
"VSS1173"
$PN"DR31"1;
"VSS1174"
$PN"DR37"1;
"VSS1175"
$PN"DR41"1;
"VSS1176"
$PN"DR43"1;
"VSS1177"
$PN"DR48"1;
"VSS1178"
$PN"DR50"1;
"VSS1179"
$PN"DR56"1;
"VSS1181"
$PN"DR66"1;
"VSS1182"
$PN"DR74"2;
"VSS1183"
$PN"DR78"2;
"VSS1184"
$PN"DR84"2;
"VSS1186"
$PN"DR88"2;
"VSS1187"
$PN"DR9"1;
"VSS1189"
$PN"DT12"2;
"VSS1190"
$PN"DT22"2;
"VSS1191"
$PN"DT28"2;
"VSS1192"
$PN"DT32"2;
"VSS1194"
$PN"DT34"2;
"VSS1196"
$PN"DT38"2;
"VSS1199"
$PN"DT40"2;
"VSS1201"
$PN"DT47"2;
"VSS1202"
$PN"DT57"2;
"VSS1203"
$PN"DT65"2;
"VSS1204"
$PN"DT69"2;
"VSS1205"
$PN"DT71"2;
"VSS1206"
$PN"DT75"2;
"VSS1207"
$PN"DT8"2;
"VSS1209"
$PN"DU21"2;
"VSS1211"
$PN"DU27"2;
"VSS1212"
$PN"DU33"2;
"VSS1213"
$PN"DU76"2;
"VSS1214"
$PN"DU78"2;
"VSS1215"
$PN"DU84"2;
"VSS1216"
$PN"DU88"2;
"VSS1218"
$PN"DV77"2;
"VSS1219"
$PN"DV79"2;
"VSS1221"
$PN"DV8"2;
"VSS1222"
$PN"DV81"2;
"VSS1226"
$PN"DV83"2;
"VSS1227"
$PN"DV87"2;
"VSS1228"
$PN"DV91"2;
"VSS1229"
$PN"DW1"2;
"VSS1230"
$PN"DW13"2;
"VSS1231"
$PN"DW17"2;
"VSS1233"
$PN"DW19"2;
"VSS1234"
$PN"DW23"2;
"VSS1236"
$PN"DW25"2;
"VSS1238"
$PN"DW27"2;
"VSS1239"
$PN"DW29"2;
"VSS1240"
$PN"DW31"2;
"VSS1241"
$PN"DW33"2;
"VSS1242"
$PN"DW35"2;
"VSS1243"
$PN"DW37"2;
"VSS1244"
$PN"DW39"2;
"VSS1245"
$PN"DW41"2;
"VSS1246"
$PN"DW43"2;
"VSS1247"
$PN"DW45"2;
"VSS1248"
$PN"DW48"2;
"VSS1249"
$PN"DW5"2;
"VSS1250"
$PN"DW50"2;
"VSS1251"
$PN"DW52"2;
"VSS1252"
$PN"DW54"2;
"VSS1253"
$PN"DW56"2;
"VSS1254"
$PN"DW58"2;
"VSS1255"
$PN"DW62"2;
"VSS1256"
$PN"DW64"2;
"VSS1268"
$PN"DW9"2;
%"UNIVERSAL_GND"
"1","(5450,-725)","0","logical_power","I9";
;
CDS_LIB"logical_power"
HDL_POWER"GND";
"A"1;
END.
